(kicad_pcb
	(version 20260206)
	(generator "pcbnew")
	(generator_version "10.0")
	(general
		(thickness 1.6)
		(legacy_teardrops no)
	)
	(paper "A4")
	(title_block
		(title "panther-plus-userver — 13130-1b_20150205.brd")
		(comment 1 "Honey Badger (Wiwynn) / footprints 270-277 of 1509")
	)
	(layers
		(0 "F.Cu" signal "TOP")
		(4 "In1.Cu" signal "L2")
		(6 "In2.Cu" signal "L3")
		(8 "In3.Cu" signal "L4")
		(10 "In4.Cu" signal "L5")
		(12 "In5.Cu" signal "L6")
		(14 "In6.Cu" signal "L7")
		(16 "In7.Cu" signal "L8")
		(18 "In8.Cu" signal "L9")
		(20 "In9.Cu" signal "L10")
		(22 "In10.Cu" signal "L11")
		(2 "B.Cu" signal "BOTTOM")
		(9 "F.Adhes" user "F.Adhesive")
		(11 "B.Adhes" user "B.Adhesive")
		(13 "F.Paste" user "Package Geometry/Pastemask Top")
		(15 "B.Paste" user "Package Geometry/Pastemask Bottom")
		(5 "F.SilkS" user "Ref Des/Silkscreen Top")
		(7 "B.SilkS" user "Ref Des/Silkscreen Bottom")
		(1 "F.Mask" user "Board Geometry/Soldermask Top")
		(3 "B.Mask" user "Board Geometry/Soldermask Bottom")
		(17 "Dwgs.User" user "User.Drawings")
		(19 "Cmts.User" user "User.Comments")
		(21 "Eco1.User" user "User.Eco1")
		(23 "Eco2.User" user "User.Eco2")
		(25 "Edge.Cuts" user "Board Geometry/Outline")
		(27 "Margin" user)
		(31 "F.CrtYd" user "Package Geometry/Place Bound Top")
		(29 "B.CrtYd" user "Package Geometry/Place Bound Bottom")
		(35 "F.Fab" user "Ref Des/Assembly Top")
		(33 "B.Fab" user "Ref Des/Assembly Bottom")
	)
	(footprint ""
		(layer "F.Cu")
		(at 141.0462 -54.8132 180)
		(property "Reference" "R123"
			(at 0 0 180)
			(layer "F.SilkS")
			(hide yes)
			(effects
				(font
					(size 1.27 1.27)
				)
			)
		)
		(property "Value" "10KR2F-2-GP"
			(at 1.7907 -1.1176 180)
			(unlocked yes)
			(layer "F.Fab")
			(hide yes)
			(effects
				(font
					(size 1.016 1.016)
					(thickness 0.1524)
				)
			)
		)
		(property "Device Type" "R402H16"
			(at 1.7907 -2.6416 180)
			(unlocked yes)
			(layer "F.Fab")
			(hide yes)
			(effects
				(font
					(size 1.016 1.016)
					(thickness 0.1524)
				)
			)
		)
		(duplicate_pad_numbers_are_jumpers no)
		(fp_rect
			(start -0.381 0.8382)
			(end 0.381 -0.8382)
			(stroke
				(width 0)
				(type default)
			)
			(fill no)
			(layer "F.CrtYd")
		)
		(fp_rect
			(start -0.381 0.8382)
			(end 0.381 -0.8382)
			(stroke
				(width 0)
				(type default)
			)
			(fill no)
			(layer "F.Fab")
		)
		(pad "1" smd custom
			(at 0 -0.4318 180)
			(size 0.127 0.127)
			(layers "F.Cu" "F.Mask" "F.Paste")
			(net "P3V3_STBY")
			(options
				(clearance outline)
				(anchor circle)
			)
			(primitives
				(gr_poly
					(pts
						(arc
							(start -0.2032 -0.2794)
							(mid -0.239121 -0.264521)
							(end -0.254 -0.2286)
						)
						(arc
							(start -0.254 0.2286)
							(mid -0.239121 0.264521)
							(end -0.2032 0.2794)
						)
						(arc
							(start 0.2032 0.2794)
							(mid 0.239121 0.264521)
							(end 0.254 0.2286)
						)
						(arc
							(start 0.254 -0.2286)
							(mid 0.239121 -0.264521)
							(end 0.2032 -0.2794)
						)
					)
					(width 0)
					(fill yes)
				)
			)
		)
		(pad "2" smd custom
			(at 0 0.4318 180)
			(size 0.127 0.127)
			(layers "F.Cu" "F.Mask" "F.Paste")
			(net "SPI_SW_INT#")
			(options
				(clearance outline)
				(anchor circle)
			)
			(primitives
				(gr_poly
					(pts
						(arc
							(start -0.2032 -0.2794)
							(mid -0.239121 -0.264521)
							(end -0.254 -0.2286)
						)
						(arc
							(start -0.254 0.2286)
							(mid -0.239121 0.264521)
							(end -0.2032 0.2794)
						)
						(arc
							(start 0.2032 0.2794)
							(mid 0.239121 0.264521)
							(end 0.254 0.2286)
						)
						(arc
							(start 0.254 -0.2286)
							(mid 0.239121 -0.264521)
							(end 0.2032 -0.2794)
						)
					)
					(width 0)
					(fill yes)
				)
			)
		)
	)
	(footprint ""
		(layer "F.Cu")
		(at 201.29881 -36.46424 180)
		(property "Reference" "PU6"
			(at 0 0 180)
			(layer "F.SilkS")
			(hide yes)
			(effects
				(font
					(size 1.27 1.27)
				)
			)
		)
		(property "Value" "IRFH4253DTRPBF-GP-U"
			(at -3.9116 -4.5085 180)
			(unlocked yes)
			(layer "F.Fab")
			(hide yes)
			(effects
				(font
					(size 1.016 1.016)
					(thickness 0.1524)
				)
			)
		)
		(property "Device Type" "DFN8A5060-G2PH40"
			(at -3.9116 -6.0325 180)
			(unlocked yes)
			(layer "F.Fab")
			(hide yes)
			(effects
				(font
					(size 1.016 1.016)
					(thickness 0.1524)
				)
			)
		)
		(duplicate_pad_numbers_are_jumpers no)
		(fp_rect
			(start -2.7559 3.3782)
			(end 2.7559 -3.3782)
			(stroke
				(width 0)
				(type default)
			)
			(fill no)
			(layer "F.CrtYd")
		)
		(fp_rect
			(start -2.7559 3.3782)
			(end 2.7559 -3.3782)
			(stroke
				(width 0)
				(type default)
			)
			(fill no)
			(layer "F.Fab")
		)
		(pad "1" smd rect
			(at 1.905 -2.796794 180)
			(size 0.6604 0.9144)
			(layers "F.Cu" "F.Mask" "F.Paste")
			(net "VR_PVDDR_A_GH1_R")
		)
		(pad "2" smd rect
			(at 0.635 -2.796794 180)
			(size 0.6604 0.9144)
			(layers "F.Cu" "F.Mask" "F.Paste")
			(net "VR_PVDDR_A_PHASE1")
		)
		(pad "3" smd rect
			(at -0.635 -2.796794 180)
			(size 0.6604 0.9144)
			(layers "F.Cu" "F.Mask" "F.Paste")
			(net "PVDDR_VIN")
		)
		(pad "4" smd rect
			(at -1.905 -2.796794 180)
			(size 0.6604 0.9144)
			(layers "F.Cu" "F.Mask" "F.Paste")
			(net "PVDDR_VIN")
		)
		(pad "5" smd rect
			(at -1.905 2.745994 180)
			(size 0.6604 1.016)
			(layers "F.Cu" "F.Mask" "F.Paste")
			(net "VR_PVDDR_A_VSW")
		)
		(pad "6" smd rect
			(at -0.635 2.745994 180)
			(size 0.6604 1.016)
			(layers "F.Cu" "F.Mask" "F.Paste")
			(net "VR_PVDDR_A_VSW")
		)
		(pad "7" smd rect
			(at 0.635 2.745994 180)
			(size 0.6604 1.016)
			(layers "F.Cu" "F.Mask" "F.Paste")
			(net "VR_PVDDR_A_VSW")
		)
		(pad "8" smd rect
			(at 1.905 2.174494 180)
			(size 0.6604 2.159)
			(layers "F.Cu" "F.Mask" "F.Paste")
			(net "VR_PVDDR_A_GL1_BG")
		)
		(pad "9" smd custom
			(at 0 0.635 180)
			(size 0.66675 0.66675)
			(layers "F.Cu" "F.Mask" "F.Paste")
			(net "GND")
			(options
				(clearance outline)
				(anchor circle)
			)
			(primitives
				(gr_poly
					(pts
						(xy -2.3241 1.3335) (xy -2.3241 -1.3335) (xy 2.3241 -1.3335) (xy 2.3241 0.1905) (xy 1.1049 0.1905)
						(xy 1.1049 1.3335)
					)
					(width 0)
					(fill yes)
				)
			)
		)
		(pad "10" smd rect
			(at 0 -1.59512 180)
			(size 4.2672 1.0414)
			(layers "F.Cu" "F.Mask" "F.Paste")
			(net "PVDDR_VIN")
		)
	)
	(footprint ""
		(layer "F.Cu")
		(at 114.427 -67.691 180)
		(property "Reference" "U2"
			(at 0 0 180)
			(layer "F.SilkS")
			(hide yes)
			(effects
				(font
					(size 1.27 1.27)
				)
			)
		)
		(property "Value" "SN74LVC1G14DCKR-GP"
			(at -2.3368 -8.6868 180)
			(unlocked yes)
			(layer "F.Fab")
			(hide yes)
			(effects
				(font
					(size 1.016 1.016)
					(thickness 0.1524)
				)
			)
		)
		(property "Device Type" "SC70-5H44"
			(at -2.3114 -10.414 180)
			(unlocked yes)
			(layer "F.Fab")
			(hide yes)
			(effects
				(font
					(size 1.016 1.016)
					(thickness 0.1524)
				)
			)
		)
		(duplicate_pad_numbers_are_jumpers no)
		(fp_line
			(start 1.0033 0.3302)
			(end -1.0033 0.3302)
			(stroke
				(width 0.1524)
				(type default)
			)
			(layer "F.SilkS")
		)
		(fp_line
			(start 1.0033 -0.3302)
			(end 1.0033 0.3302)
			(stroke
				(width 0.1524)
				(type default)
			)
			(layer "F.SilkS")
		)
		(fp_line
			(start -1.0033 0.3302)
			(end -1.0033 -0.3302)
			(stroke
				(width 0.1524)
				(type default)
			)
			(layer "F.SilkS")
		)
		(fp_line
			(start -1.0033 -0.3302)
			(end 1.0033 -0.3302)
			(stroke
				(width 0.1524)
				(type default)
			)
			(layer "F.SilkS")
		)
		(fp_poly
			(pts
				(xy -1.0033 1.4859) (xy -1.0033 0.8001) (xy -1.1811 0.8001) (xy -1.1811 -0.8001) (xy -1.0033 -0.8001)
				(xy -1.0033 -1.4859) (xy 1.0033 -1.4859) (xy 1.0033 -0.8001) (xy 1.1811 -0.8001) (xy 1.1811 0.8001)
				(xy 1.0033 0.8001) (xy 1.0033 1.4859) (xy 0.2921 1.4859) (xy 0.2921 0.8001) (xy -0.2921 0.8001)
				(xy -0.2921 1.4859)
			)
			(stroke
				(width 0)
				(type default)
			)
			(fill no)
			(layer "F.CrtYd")
		)
		(fp_poly
			(pts
				(xy -1.0033 1.4859) (xy -1.0033 0.8001) (xy -1.1811 0.8001) (xy -1.1811 -0.8001) (xy -1.0033 -0.8001)
				(xy -1.0033 -1.4859) (xy 1.0033 -1.4859) (xy 1.0033 -0.8001) (xy 1.1811 -0.8001) (xy 1.1811 0.8001)
				(xy 1.0033 0.8001) (xy 1.0033 1.4859) (xy 0.2921 1.4859) (xy 0.2921 0.8001) (xy -0.2921 0.8001)
				(xy -0.2921 1.4859)
			)
			(stroke
				(width 0)
				(type default)
			)
			(fill no)
			(layer "F.Fab")
		)
		(pad "1" smd rect
			(at 0.65024 -0.93472 180)
			(size 0.3556 0.762)
			(layers "F.Cu" "F.Mask" "F.Paste")
			(net "Net_444")
		)
		(pad "2" smd rect
			(at 0 -0.93472 180)
			(size 0.3556 0.762)
			(layers "F.Cu" "F.Mask" "F.Paste")
			(net "CLK_GEN_INA_PG")
		)
		(pad "3" smd rect
			(at -0.65024 -0.93472 180)
			(size 0.3556 0.762)
			(layers "F.Cu" "F.Mask" "F.Paste")
			(net "GND")
		)
		(pad "4" smd rect
			(at -0.65024 0.93472 180)
			(size 0.3556 0.762)
			(layers "F.Cu" "F.Mask" "F.Paste")
			(net "CLK_GEN_OUT")
		)
		(pad "5" smd rect
			(at 0.65024 0.93472 180)
			(size 0.3556 0.762)
			(layers "F.Cu" "F.Mask" "F.Paste")
			(net "P3V3_STBY")
		)
	)
	(footprint ""
		(layer "F.Cu")
		(at 200.914 -28.956 -90)
		(property "Reference" "PC175"
			(at 0 0 270)
			(layer "F.SilkS")
			(hide yes)
			(effects
				(font
					(size 1.27 1.27)
				)
			)
		)
		(property "Value" "SC10U25V5KX-GP"
			(at 0 -4.9022 270)
			(unlocked yes)
			(layer "F.Fab")
			(hide yes)
			(effects
				(font
					(size 1.016 1.016)
					(thickness 0.1524)
				)
			)
		)
		(property "Device Type" "C805H56"
			(at 0 -6.8072 270)
			(unlocked yes)
			(layer "F.Fab")
			(hide yes)
			(effects
				(font
					(size 1.016 1.016)
					(thickness 0.1524)
				)
			)
		)
		(duplicate_pad_numbers_are_jumpers no)
		(fp_line
			(start 0.6096 0)
			(end -0.6096 0)
			(stroke
				(width 0.3048)
				(type default)
			)
			(layer "F.SilkS")
		)
		(fp_poly
			(pts
				(xy -0.9017 1.4351) (xy 0.9017 1.4351) (xy 0.9017 -1.4351) (xy -0.9017 -1.4351)
			)
			(stroke
				(width 0)
				(type default)
			)
			(fill no)
			(layer "F.CrtYd")
		)
		(fp_poly
			(pts
				(xy 0.9017 1.4351) (xy 0.9017 -1.4351) (xy -0.9017 -1.4351) (xy -0.9017 1.4351)
			)
			(stroke
				(width 0)
				(type default)
			)
			(fill no)
			(layer "F.Fab")
		)
		(pad "1" smd rect
			(at 0 -0.8382 270)
			(size 1.5494 0.9398)
			(layers "F.Cu" "F.Mask" "F.Paste")
			(net "PVDDR_VIN")
		)
		(pad "2" smd rect
			(at 0 0.8382 270)
			(size 1.5494 0.9398)
			(layers "F.Cu" "F.Mask" "F.Paste")
			(net "GND")
		)
	)
	(footprint ""
		(layer "F.Cu")
		(at 63.6524 -63.754 180)
		(property "Reference" "PC135"
			(at 0 0 180)
			(layer "F.SilkS")
			(hide yes)
			(effects
				(font
					(size 1.27 1.27)
				)
			)
		)
		(property "Value" "SC47U6D3V5MX-1-GP"
			(at -0.0762 -6.1214 180)
			(unlocked yes)
			(layer "F.Fab")
			(hide yes)
			(effects
				(font
					(size 1.016 1.016)
					(thickness 0.1524)
				)
			)
		)
		(property "Device Type" "C805H54"
			(at -0.0762 -8.1534 180)
			(unlocked yes)
			(layer "F.Fab")
			(hide yes)
			(effects
				(font
					(size 1.016 1.016)
					(thickness 0.1524)
				)
			)
		)
		(duplicate_pad_numbers_are_jumpers no)
		(fp_line
			(start 0.6096 0)
			(end -0.6096 0)
			(stroke
				(width 0.3048)
				(type default)
			)
			(layer "F.SilkS")
		)
		(fp_poly
			(pts
				(xy -0.9017 1.4351) (xy 0.9017 1.4351) (xy 0.9017 -1.4351) (xy -0.9017 -1.4351)
			)
			(stroke
				(width 0)
				(type default)
			)
			(fill no)
			(layer "F.CrtYd")
		)
		(fp_poly
			(pts
				(xy 0.9017 1.4351) (xy 0.9017 -1.4351) (xy -0.9017 -1.4351) (xy -0.9017 1.4351)
			)
			(stroke
				(width 0)
				(type default)
			)
			(fill no)
			(layer "F.Fab")
		)
		(pad "1" smd rect
			(at 0 -0.8382 180)
			(size 1.5494 0.9398)
			(layers "F.Cu" "F.Mask" "F.Paste")
			(net "PVCCP")
		)
		(pad "2" smd rect
			(at 0 0.8382 180)
			(size 1.5494 0.9398)
			(layers "F.Cu" "F.Mask" "F.Paste")
			(net "GND")
		)
	)
	(footprint ""
		(layer "F.Cu")
		(at 27.0764 -54.3814 90)
		(property "Reference" "PC46"
			(at 0 0 90)
			(layer "F.SilkS")
			(hide yes)
			(effects
				(font
					(size 1.27 1.27)
				)
			)
		)
		(property "Value" "SCD22U16V3KX-2-GP"
			(at -0.0254 -2.0193 90)
			(unlocked yes)
			(layer "F.Fab")
			(hide yes)
			(effects
				(font
					(size 1.016 1.016)
					(thickness 0.1524)
				)
			)
		)
		(property "Device Type" "C603H36"
			(at -0.0254 -3.5433 90)
			(unlocked yes)
			(layer "F.Fab")
			(hide yes)
			(effects
				(font
					(size 1.016 1.016)
					(thickness 0.1524)
				)
			)
		)
		(duplicate_pad_numbers_are_jumpers no)
		(fp_line
			(start -0.4064 0)
			(end 0.4064 0)
			(stroke
				(width 0.2286)
				(type default)
			)
			(layer "F.SilkS")
		)
		(fp_rect
			(start -0.635 1.1811)
			(end 0.635 -1.1811)
			(stroke
				(width 0)
				(type default)
			)
			(fill no)
			(layer "F.CrtYd")
		)
		(fp_rect
			(start -0.635 1.1811)
			(end 0.635 -1.1811)
			(stroke
				(width 0)
				(type default)
			)
			(fill no)
			(layer "F.Fab")
		)
		(pad "1" smd custom
			(at 0 -0.6604 90)
			(size 0.19685 0.19685)
			(layers "F.Cu" "F.Mask" "F.Paste")
			(net "VR_PVCCP_BOOT")
			(options
				(clearance outline)
				(anchor circle)
			)
			(primitives
				(gr_poly
					(pts
						(arc
							(start 0.508 -0.2921)
							(mid 0.478242 -0.363942)
							(end 0.4064 -0.3937)
						)
						(arc
							(start -0.4064 -0.3937)
							(mid -0.478242 -0.363942)
							(end -0.508 -0.2921)
						)
						(arc
							(start -0.508 0.2921)
							(mid -0.478242 0.363942)
							(end -0.4064 0.3937)
						)
						(arc
							(start 0.4064 0.3937)
							(mid 0.478242 0.363942)
							(end 0.508 0.2921)
						)
					)
					(width 0)
					(fill yes)
				)
			)
		)
		(pad "2" smd custom
			(at 0 0.6604 90)
			(size 0.19685 0.19685)
			(layers "F.Cu" "F.Mask" "F.Paste")
			(net "VR_PVCCP_BOOT_R")
			(options
				(clearance outline)
				(anchor circle)
			)
			(primitives
				(gr_poly
					(pts
						(arc
							(start 0.508 -0.2921)
							(mid 0.478242 -0.363942)
							(end 0.4064 -0.3937)
						)
						(arc
							(start -0.4064 -0.3937)
							(mid -0.478242 -0.363942)
							(end -0.508 -0.2921)
						)
						(arc
							(start -0.508 0.2921)
							(mid -0.478242 0.363942)
							(end -0.4064 0.3937)
						)
						(arc
							(start 0.4064 0.3937)
							(mid 0.478242 0.363942)
							(end 0.508 0.2921)
						)
					)
					(width 0)
					(fill yes)
				)
			)
		)
	)
	(footprint ""
		(layer "F.Cu")
		(at 48.26 -20.955)
		(property "Reference" "R169"
			(at 0 0 0)
			(layer "F.SilkS")
			(hide yes)
			(effects
				(font
					(size 1.27 1.27)
				)
			)
		)
		(property "Value" "15R2F-2-GP"
			(at 0.064008 -3.993896 0)
			(unlocked yes)
			(layer "F.Fab")
			(hide yes)
			(effects
				(font
					(size 1.016 1.016)
					(thickness 0.1524)
				)
			)
		)
		(property "Device Type" "R402H16"
			(at 0.064008 -5.517896 0)
			(unlocked yes)
			(layer "F.Fab")
			(hide yes)
			(effects
				(font
					(size 1.016 1.016)
					(thickness 0.1524)
				)
			)
		)
		(duplicate_pad_numbers_are_jumpers no)
		(fp_rect
			(start -0.381 0.8382)
			(end 0.381 -0.8382)
			(stroke
				(width 0)
				(type default)
			)
			(fill no)
			(layer "F.CrtYd")
		)
		(fp_rect
			(start -0.381 0.8382)
			(end 0.381 -0.8382)
			(stroke
				(width 0)
				(type default)
			)
			(fill no)
			(layer "F.Fab")
		)
		(pad "1" smd custom
			(at 0 -0.4318)
			(size 0.127 0.127)
			(layers "F.Cu" "F.Mask" "F.Paste")
			(net "SPI_MISO_R_GBE")
			(options
				(clearance outline)
				(anchor circle)
			)
			(primitives
				(gr_poly
					(pts
						(arc
							(start -0.2032 -0.2794)
							(mid -0.239121 -0.264521)
							(end -0.254 -0.2286)
						)
						(arc
							(start -0.254 0.2286)
							(mid -0.239121 0.264521)
							(end -0.2032 0.2794)
						)
						(arc
							(start 0.2032 0.2794)
							(mid 0.239121 0.264521)
							(end 0.254 0.2286)
						)
						(arc
							(start 0.254 -0.2286)
							(mid 0.239121 -0.264521)
							(end 0.2032 -0.2794)
						)
					)
					(width 0)
					(fill yes)
				)
			)
		)
		(pad "2" smd custom
			(at 0 0.4318)
			(size 0.127 0.127)
			(layers "F.Cu" "F.Mask" "F.Paste")
			(net "SO_GBE")
			(options
				(clearance outline)
				(anchor circle)
			)
			(primitives
				(gr_poly
					(pts
						(arc
							(start -0.2032 -0.2794)
							(mid -0.239121 -0.264521)
							(end -0.254 -0.2286)
						)
						(arc
							(start -0.254 0.2286)
							(mid -0.239121 0.264521)
							(end -0.2032 0.2794)
						)
						(arc
							(start 0.2032 0.2794)
							(mid 0.239121 0.264521)
							(end 0.254 0.2286)
						)
						(arc
							(start 0.254 -0.2286)
							(mid 0.239121 -0.264521)
							(end 0.2032 -0.2794)
						)
					)
					(width 0)
					(fill yes)
				)
			)
		)
	)
	(footprint ""
		(layer "F.Cu")
		(at 74.9554 -38.481 -90)
		(property "Reference" "R487"
			(at 0 0 270)
			(layer "F.SilkS")
			(hide yes)
			(effects
				(font
					(size 1.27 1.27)
				)
			)
		)
		(property "Value" "51R2F-2-GP"
			(at 1.7907 -1.1176 270)
			(unlocked yes)
			(layer "F.Fab")
			(hide yes)
			(effects
				(font
					(size 1.016 1.016)
					(thickness 0.1524)
				)
			)
		)
		(property "Device Type" "R402H16"
			(at 1.7907 -2.6416 270)
			(unlocked yes)
			(layer "F.Fab")
			(hide yes)
			(effects
				(font
					(size 1.016 1.016)
					(thickness 0.1524)
				)
			)
		)
		(duplicate_pad_numbers_are_jumpers no)
		(fp_rect
			(start -0.381 0.8382)
			(end 0.381 -0.8382)
			(stroke
				(width 0)
				(type default)
			)
			(fill no)
			(layer "F.CrtYd")
		)
		(fp_rect
			(start -0.381 0.8382)
			(end 0.381 -0.8382)
			(stroke
				(width 0)
				(type default)
			)
			(fill no)
			(layer "F.Fab")
		)
		(pad "1" smd custom
			(at 0 -0.4318 270)
			(size 0.127 0.127)
			(layers "F.Cu" "F.Mask" "F.Paste")
			(net "XDP_SOC_CPU_TDO")
			(options
				(clearance outline)
				(anchor circle)
			)
			(primitives
				(gr_poly
					(pts
						(arc
							(start -0.2032 -0.2794)
							(mid -0.239121 -0.264521)
							(end -0.254 -0.2286)
						)
						(arc
							(start -0.254 0.2286)
							(mid -0.239121 0.264521)
							(end -0.2032 0.2794)
						)
						(arc
							(start 0.2032 0.2794)
							(mid 0.239121 0.264521)
							(end 0.254 0.2286)
						)
						(arc
							(start 0.254 -0.2286)
							(mid 0.239121 -0.264521)
							(end 0.2032 -0.2794)
						)
					)
					(width 0)
					(fill yes)
				)
			)
		)
		(pad "2" smd custom
			(at 0 0.4318 270)
			(size 0.127 0.127)
			(layers "F.Cu" "F.Mask" "F.Paste")
			(net "GND")
			(options
				(clearance outline)
				(anchor circle)
			)
			(primitives
				(gr_poly
					(pts
						(arc
							(start -0.2032 -0.2794)
							(mid -0.239121 -0.264521)
							(end -0.254 -0.2286)
						)
						(arc
							(start -0.254 0.2286)
							(mid -0.239121 0.264521)
							(end -0.2032 0.2794)
						)
						(arc
							(start 0.2032 0.2794)
							(mid 0.239121 0.264521)
							(end 0.254 0.2286)
						)
						(arc
							(start 0.254 -0.2286)
							(mid 0.239121 -0.264521)
							(end 0.2032 -0.2794)
						)
					)
					(width 0)
					(fill yes)
				)
			)
		)
	)
)
